# T6G (Grand Teton) — schematic netlist excerpt (pin names and nets, part order shuffled) for the footprints in the layout excerpt that follows; sources: Cadence DE-HDL packaged netlist, KiCad conversion of 04192023_DAF0TMB3IC0_F0TG_MB_C_brd_V02_OCP.brd

PR227  Q_RES  49.9 1% CHIP  pkg 0402LF  page 217 : A = VSENSE_PVDDIO_P1_DP ; B = PVDDIO_P1
C6089  Q_CAP  1UF 25V 10% X6S  pkg C0402  page 178 : A = USB_HUB2_TI_GRSTZ_MRP_PROG_FUNC1 ; B = GND

(kicad_pcb
	(version 20260206)
	(generator "pcbnew")
	(generator_version "10.0")
	(general
		(thickness 1.6)
		(legacy_teardrops no)
	)
	(paper "A4")
	(title_block
		(title "04192023_DAF0TMB3IC0_F0TG_MB_C_brd_V02_OCP.brd")
		(comment 1 "Grand Teton / footprints 4909-4910 of 8354")
	)
	(layers
		(0 "F.Cu" signal "TOP")
		(4 "In1.Cu" signal "GND")
		(6 "In2.Cu" signal "IN1")
		(8 "In3.Cu" signal "GND1")
		(10 "In4.Cu" signal "IN2")
		(12 "In5.Cu" signal "GND2")
		(14 "In6.Cu" signal "IN3")
		(16 "In7.Cu" signal "GND3")
		(18 "In8.Cu" signal "VCC")
		(20 "In9.Cu" signal "VCC1")
		(22 "In10.Cu" signal "GND4")
		(24 "In11.Cu" signal "IN4")
		(26 "In12.Cu" signal "GND5")
		(28 "In13.Cu" signal "IN5")
		(30 "In14.Cu" signal "GND6")
		(32 "In15.Cu" signal "IN6")
		(34 "In16.Cu" signal "GND7")
		(2 "B.Cu" signal "BOTTOM")
		(9 "F.Adhes" user "F.Adhesive")
		(11 "B.Adhes" user "B.Adhesive")
		(13 "F.Paste" user "Package Geometry/Pastemask Top")
		(15 "B.Paste" user "Package Geometry/Pastemask Bottom")
		(5 "F.SilkS" user "Ref Des/Silkscreen Top")
		(7 "B.SilkS" user "Ref Des/Silkscreen Bottom")
		(1 "F.Mask" user "Board Geometry/Soldermask Top")
		(3 "B.Mask" user "Board Geometry/Soldermask Bottom")
		(17 "Dwgs.User" user "User.Drawings")
		(19 "Cmts.User" user "User.Comments")
		(21 "Eco1.User" user "User.Eco1")
		(23 "Eco2.User" user "User.Eco2")
		(25 "Edge.Cuts" user "Board Geometry/Outline")
		(27 "Margin" user)
		(31 "F.CrtYd" user "Package Geometry/Place Bound Top")
		(29 "B.CrtYd" user "Package Geometry/Place Bound Bottom")
		(35 "F.Fab" user "Ref Des/Assembly Top")
		(33 "B.Fab" user "Ref Des/Assembly Bottom")
	)
	(footprint ""
		(layer "F.Cu")
		(at 22.49297 -332.104746)
		(property "Reference" "PR227"
			(at 0 0 0)
			(layer "F.SilkS")
			(hide yes)
			(effects
				(font
					(size 1.27 1.27)
				)
			)
		)
		(property "Value" ""
			(at 0 0 0)
			(layer "F.Fab")
			(effects
				(font
					(size 1.27 1.27)
				)
			)
		)
		(duplicate_pad_numbers_are_jumpers no)
		(fp_line
			(start -0.7874 -0.4064)
			(end 0.7874 -0.4064)
			(stroke
				(width 0.1524)
				(type default)
			)
			(layer "F.SilkS")
		)
		(fp_line
			(start -0.7874 0.4064)
			(end -0.7874 -0.4064)
			(stroke
				(width 0.1524)
				(type default)
			)
			(layer "F.SilkS")
		)
		(fp_line
			(start 0.7874 -0.4064)
			(end 0.7874 0.4064)
			(stroke
				(width 0.1524)
				(type default)
			)
			(layer "F.SilkS")
		)
		(fp_line
			(start 0.7874 0.4064)
			(end -0.7874 0.4064)
			(stroke
				(width 0.1524)
				(type default)
			)
			(layer "F.SilkS")
		)
		(fp_line
			(start -0.67945 -0.305054)
			(end -0.12065 -0.305054)
			(stroke
				(width 0.1)
				(type default)
			)
			(layer "F.Fab")
		)
		(fp_line
			(start -0.67945 0.3048)
			(end -0.67945 -0.305054)
			(stroke
				(width 0.1)
				(type default)
			)
			(layer "F.Fab")
		)
		(fp_line
			(start -0.12065 -0.305054)
			(end -0.12065 -0.2794)
			(stroke
				(width 0.1)
				(type default)
			)
			(layer "F.Fab")
		)
		(fp_line
			(start -0.12065 -0.2794)
			(end 0.12065 -0.2794)
			(stroke
				(width 0.1)
				(type default)
			)
			(layer "F.Fab")
		)
		(fp_line
			(start -0.12065 0.2794)
			(end -0.12065 0.3048)
			(stroke
				(width 0.1)
				(type default)
			)
			(layer "F.Fab")
		)
		(fp_line
			(start -0.12065 0.3048)
			(end -0.67945 0.3048)
			(stroke
				(width 0.1)
				(type default)
			)
			(layer "F.Fab")
		)
		(fp_line
			(start 0.120396 0.2794)
			(end -0.12065 0.2794)
			(stroke
				(width 0.1)
				(type default)
			)
			(layer "F.Fab")
		)
		(fp_line
			(start 0.120396 0.3048)
			(end 0.120396 0.2794)
			(stroke
				(width 0.1)
				(type default)
			)
			(layer "F.Fab")
		)
		(fp_line
			(start 0.12065 -0.3048)
			(end 0.67945 -0.3048)
			(stroke
				(width 0.1)
				(type default)
			)
			(layer "F.Fab")
		)
		(fp_line
			(start 0.12065 -0.2794)
			(end 0.12065 -0.3048)
			(stroke
				(width 0.1)
				(type default)
			)
			(layer "F.Fab")
		)
		(fp_line
			(start 0.67945 -0.3048)
			(end 0.67945 0.3048)
			(stroke
				(width 0.1)
				(type default)
			)
			(layer "F.Fab")
		)
		(fp_line
			(start 0.67945 0.3048)
			(end 0.120396 0.3048)
			(stroke
				(width 0.1)
				(type default)
			)
			(layer "F.Fab")
		)
		(pad "1" smd circle
			(at -0.40005 0)
			(size 0 0)
			(layers "F.Cu" "F.Mask" "F.Paste")
			(net "VSENSE_PVDDIO_P1_DP")
		)
		(pad "2" smd circle
			(at 0.40005 0)
			(size 0 0)
			(layers "F.Cu" "F.Mask" "F.Paste")
			(net "PVDDIO_P1")
		)
	)
	(footprint ""
		(layer "F.Cu")
		(at 98.222562 -31.835598 -90)
		(property "Reference" "C6089"
			(at 0 0 270)
			(layer "F.SilkS")
			(hide yes)
			(effects
				(font
					(size 1.27 1.27)
				)
			)
		)
		(property "Value" ""
			(at 0 0 270)
			(layer "F.Fab")
			(effects
				(font
					(size 1.27 1.27)
				)
			)
		)
		(duplicate_pad_numbers_are_jumpers no)
		(fp_line
			(start -0.7874 0.4064)
			(end -0.7874 -0.4064)
			(stroke
				(width 0.1524)
				(type default)
			)
			(layer "F.SilkS")
		)
		(fp_line
			(start 0.7874 0.4064)
			(end -0.7874 0.4064)
			(stroke
				(width 0.1524)
				(type default)
			)
			(layer "F.SilkS")
		)
		(fp_line
			(start -0.7874 -0.4064)
			(end 0.7874 -0.4064)
			(stroke
				(width 0.1524)
				(type default)
			)
			(layer "F.SilkS")
		)
		(fp_line
			(start 0.7874 -0.4064)
			(end 0.7874 0.4064)
			(stroke
				(width 0.1524)
				(type default)
			)
			(layer "F.SilkS")
		)
		(fp_line
			(start -0.67945 0.3048)
			(end -0.67945 -0.305054)
			(stroke
				(width 0.1)
				(type default)
			)
			(layer "F.Fab")
		)
		(fp_line
			(start -0.12065 0.3048)
			(end -0.67945 0.3048)
			(stroke
				(width 0.1)
				(type default)
			)
			(layer "F.Fab")
		)
		(fp_line
			(start 0.120396 0.3048)
			(end 0.120396 0.2794)
			(stroke
				(width 0.1)
				(type default)
			)
			(layer "F.Fab")
		)
		(fp_line
			(start 0.67945 0.3048)
			(end 0.120396 0.3048)
			(stroke
				(width 0.1)
				(type default)
			)
			(layer "F.Fab")
		)
		(fp_line
			(start -0.12065 0.2794)
			(end -0.12065 0.3048)
			(stroke
				(width 0.1)
				(type default)
			)
			(layer "F.Fab")
		)
		(fp_line
			(start 0.120396 0.2794)
			(end -0.12065 0.2794)
			(stroke
				(width 0.1)
				(type default)
			)
			(layer "F.Fab")
		)
		(fp_line
			(start -0.12065 -0.2794)
			(end 0.12065 -0.2794)
			(stroke
				(width 0.1)
				(type default)
			)
			(layer "F.Fab")
		)
		(fp_line
			(start 0.12065 -0.2794)
			(end 0.12065 -0.3048)
			(stroke
				(width 0.1)
				(type default)
			)
			(layer "F.Fab")
		)
		(fp_line
			(start 0.12065 -0.3048)
			(end 0.67945 -0.3048)
			(stroke
				(width 0.1)
				(type default)
			)
			(layer "F.Fab")
		)
		(fp_line
			(start 0.67945 -0.3048)
			(end 0.67945 0.3048)
			(stroke
				(width 0.1)
				(type default)
			)
			(layer "F.Fab")
		)
		(fp_line
			(start -0.67945 -0.305054)
			(end -0.12065 -0.305054)
			(stroke
				(width 0.1)
				(type default)
			)
			(layer "F.Fab")
		)
		(fp_line
			(start -0.12065 -0.305054)
			(end -0.12065 -0.2794)
			(stroke
				(width 0.1)
				(type default)
			)
			(layer "F.Fab")
		)
		(pad "1" smd circle
			(at -0.40005 0 270)
			(size 0 0)
			(layers "F.Cu" "F.Mask" "F.Paste")
			(net "USB_HUB2_TI_GRSTZ_MRP_PROG_FUNC1")
		)
		(pad "2" smd circle
			(at 0.40005 0 270)
			(size 0 0)
			(layers "F.Cu" "F.Mask" "F.Paste")
			(net "GND")
		)
	)
)
